(kicad_pcb
	(version 20260206)
	(generator "pcbnew")
	(generator_version "10.0")
	(general
		(thickness 1.6)
		(legacy_teardrops no)
	)
	(paper "A4")
	(title_block
		(title "Bryce Canyon_R.DPB_16317-1_OCP.brd")
		(comment 1 "Bryce Canyon / footprints 1337-1345 of 2099")
	)
	(layers
		(0 "F.Cu" signal "TOP")
		(4 "In1.Cu" signal "L2GND")
		(6 "In2.Cu" signal "L3")
		(8 "In3.Cu" signal "L4VCC")
		(10 "In4.Cu" signal "L5VCC")
		(12 "In5.Cu" signal "L6")
		(14 "In6.Cu" signal "L7GND")
		(2 "B.Cu" signal "BOTTOM")
		(9 "F.Adhes" user "F.Adhesive")
		(11 "B.Adhes" user "B.Adhesive")
		(13 "F.Paste" user "Package Geometry/Pastemask Top")
		(15 "B.Paste" user "Package Geometry/Pastemask Bottom")
		(5 "F.SilkS" user "Ref Des/Silkscreen Top")
		(7 "B.SilkS" user "Ref Des/Silkscreen Bottom")
		(1 "F.Mask" user "Board Geometry/Soldermask Top")
		(3 "B.Mask" user "Board Geometry/Soldermask Bottom")
		(17 "Dwgs.User" user "User.Drawings")
		(19 "Cmts.User" user "User.Comments")
		(21 "Eco1.User" user "User.Eco1")
		(23 "Eco2.User" user "User.Eco2")
		(25 "Edge.Cuts" user "Board Geometry/Outline")
		(27 "Margin" user)
		(31 "F.CrtYd" user "Package Geometry/Place Bound Top")
		(29 "B.CrtYd" user "Package Geometry/Place Bound Bottom")
		(35 "F.Fab" user "Ref Des/Assembly Top")
		(33 "B.Fab" user "Ref Des/Assembly Bottom")
	)
	(footprint ""
		(layer "F.Cu")
		(at 259.089906 -228.84511 -90)
		(property "Reference" "R168"
			(at 0 0 270)
			(layer "F.SilkS")
			(hide yes)
			(effects
				(font
					(size 1.27 1.27)
				)
			)
		)
		(property "Value" "16K2R2F-GP"
			(at 0.064008 -3.993896 270)
			(unlocked yes)
			(layer "F.Fab")
			(hide yes)
			(effects
				(font
					(size 1.016 1.016)
					(thickness 0.1524)
				)
			)
		)
		(property "Device Type" "R402H16"
			(at 0.064008 -5.517896 270)
			(unlocked yes)
			(layer "F.Fab")
			(hide yes)
			(effects
				(font
					(size 1.016 1.016)
					(thickness 0.1524)
				)
			)
		)
		(duplicate_pad_numbers_are_jumpers no)
		(fp_line
			(start -0.508 -0.9398)
			(end -0.508 0.9398)
			(stroke
				(width 0.1524)
				(type default)
			)
			(layer "F.SilkS")
		)
		(fp_line
			(start 0.508 -0.9398)
			(end -0.508 -0.9398)
			(stroke
				(width 0.1524)
				(type default)
			)
			(layer "F.SilkS")
		)
		(fp_rect
			(start -0.508 0.9398)
			(end 0.508 -0.9398)
			(stroke
				(width 0)
				(type default)
			)
			(fill no)
			(layer "F.CrtYd")
		)
		(fp_rect
			(start -0.508 0.9398)
			(end 0.508 -0.9398)
			(stroke
				(width 0)
				(type default)
			)
			(fill no)
			(layer "F.Fab")
		)
		(pad "1" smd custom
			(at 0 -0.4445 270)
			(size 0.1397 0.1397)
			(layers "F.Cu" "F.Mask" "F.Paste")
			(net "P5V_B_3")
			(options
				(clearance outline)
				(anchor circle)
			)
			(primitives
				(gr_poly
					(pts
						(arc
							(start -0.1778 -0.2794)
							(mid -0.249642 -0.249642)
							(end -0.2794 -0.1778)
						)
						(arc
							(start -0.2794 0.1778)
							(mid -0.249642 0.249642)
							(end -0.1778 0.2794)
						)
						(arc
							(start 0.1778 0.2794)
							(mid 0.249642 0.249642)
							(end 0.2794 0.1778)
						)
						(arc
							(start 0.2794 -0.1778)
							(mid 0.249642 -0.249642)
							(end 0.1778 -0.2794)
						)
					)
					(width 0)
					(fill yes)
				)
			)
		)
		(pad "2" smd custom
			(at 0 0.4445 270)
			(size 0.1397 0.1397)
			(layers "F.Cu" "F.Mask" "F.Paste")
			(net "P5V_B_3_SENSE")
			(options
				(clearance outline)
				(anchor circle)
			)
			(primitives
				(gr_poly
					(pts
						(arc
							(start -0.1778 -0.2794)
							(mid -0.249642 -0.249642)
							(end -0.2794 -0.1778)
						)
						(arc
							(start -0.2794 0.1778)
							(mid -0.249642 0.249642)
							(end -0.1778 0.2794)
						)
						(arc
							(start 0.1778 0.2794)
							(mid 0.249642 0.249642)
							(end 0.2794 0.1778)
						)
						(arc
							(start 0.2794 -0.1778)
							(mid 0.249642 -0.249642)
							(end 0.1778 -0.2794)
						)
					)
					(width 0)
					(fill yes)
				)
			)
		)
	)
	(footprint ""
		(layer "F.Cu")
		(at 459.613 -160.02 180)
		(property "Reference" "C322"
			(at 0 0 180)
			(layer "F.SilkS")
			(hide yes)
			(effects
				(font
					(size 1.27 1.27)
				)
			)
		)
		(property "Value" "SC4D7U25V5KX-1-GP"
			(at -0.0762 -6.1214 180)
			(unlocked yes)
			(layer "F.Fab")
			(hide yes)
			(effects
				(font
					(size 1.016 1.016)
					(thickness 0.1524)
				)
			)
		)
		(property "Device Type" "C805H58"
			(at -0.0762 -8.1534 180)
			(unlocked yes)
			(layer "F.Fab")
			(hide yes)
			(effects
				(font
					(size 1.016 1.016)
					(thickness 0.1524)
				)
			)
		)
		(duplicate_pad_numbers_are_jumpers no)
		(fp_line
			(start 0.635 0)
			(end -0.635 0)
			(stroke
				(width 0.508)
				(type default)
			)
			(layer "F.SilkS")
		)
		(fp_rect
			(start -0.9652 1.778)
			(end 0.9652 -1.778)
			(stroke
				(width 0)
				(type default)
			)
			(fill no)
			(layer "F.CrtYd")
		)
		(fp_poly
			(pts
				(xy -0.9652 -1.778) (xy 0.9652 -1.778) (xy 0.9652 1.778) (xy -0.9652 1.778)
			)
			(stroke
				(width 0)
				(type default)
			)
			(fill no)
			(layer "F.Fab")
		)
		(pad "1" smd rect
			(at 0 -0.9652 180)
			(size 1.397 1.143)
			(layers "F.Cu" "F.Mask" "F.Paste")
			(net "P12V_HDD22")
		)
		(pad "2" smd rect
			(at 0 0.9652 180)
			(size 1.397 1.143)
			(layers "F.Cu" "F.Mask" "F.Paste")
			(net "GND")
		)
	)
	(footprint ""
		(layer "F.Cu")
		(at 351.336102 -128.627124 180)
		(property "Reference" "VIA39"
			(at 0 0 180)
			(layer "F.SilkS")
			(hide yes)
			(effects
				(font
					(size 1.27 1.27)
				)
			)
		)
		(property "Value" "100OHM-8L-2D36MM-L18-GP"
			(at 3.8989 0.5715 180)
			(unlocked yes)
			(layer "F.Fab")
			(hide yes)
			(effects
				(font
					(size 1.016 1.016)
					(thickness 0.1524)
				)
			)
		)
		(property "Device Type" "VIA-PCIE-4P-414097"
			(at 3.8989 -0.9525 180)
			(unlocked yes)
			(layer "F.Fab")
			(hide yes)
			(effects
				(font
					(size 1.016 1.016)
					(thickness 0.1524)
				)
			)
		)
		(duplicate_pad_numbers_are_jumpers no)
		(fp_rect
			(start -2.0701 0.4826)
			(end 2.0701 -0.4826)
			(stroke
				(width 0)
				(type default)
			)
			(fill no)
			(layer "F.CrtYd")
		)
		(fp_rect
			(start -2.0701 0.4826)
			(end 2.0701 -0.4826)
			(stroke
				(width 0)
				(type default)
			)
			(fill no)
			(layer "F.Fab")
		)
		(pad "1" thru_hole circle
			(at -1.5875 0 180)
			(size 0.508 0.508)
			(drill 0.254)
			(layers "*.Cu" "*.Mask")
			(remove_unused_layers no)
			(net "GND")
			(clearance 0.2286)
			(thermal_gap 0.2286)
		)
		(pad "2" thru_hole circle
			(at -0.5715 0 180)
			(size 0.508 0.508)
			(drill 0.254)
			(layers "*.Cu" "*.Mask")
			(remove_unused_layers no)
			(net "PHY_SCC_B_TO_DRV_B_19_DP")
			(clearance 0.2286)
			(thermal_gap 0.2286)
		)
		(pad "3" thru_hole circle
			(at 0.5715 0 180)
			(size 0.508 0.508)
			(drill 0.254)
			(layers "*.Cu" "*.Mask")
			(remove_unused_layers no)
			(net "PHY_SCC_B_TO_DRV_B_19_DN")
			(clearance 0.2286)
			(thermal_gap 0.2286)
		)
		(pad "4" thru_hole circle
			(at 1.5875 0 180)
			(size 0.508 0.508)
			(drill 0.254)
			(layers "*.Cu" "*.Mask")
			(remove_unused_layers no)
			(net "GND")
			(clearance 0.2286)
			(thermal_gap 0.2286)
		)
	)
	(footprint ""
		(layer "F.Cu")
		(at 158.496 -31.623)
		(property "Reference" "C400"
			(at 0 0 0)
			(layer "F.SilkS")
			(hide yes)
			(effects
				(font
					(size 1.27 1.27)
				)
			)
		)
		(property "Value" "SCD01U50V2KX-1GP"
			(at 1.1811 -2.7051 0)
			(unlocked yes)
			(layer "F.Fab")
			(hide yes)
			(effects
				(font
					(size 1.016 1.016)
					(thickness 0.1524)
				)
			)
		)
		(property "Device Type" "C402H22"
			(at 1.1811 -4.2291 0)
			(unlocked yes)
			(layer "F.Fab")
			(hide yes)
			(effects
				(font
					(size 1.016 1.016)
					(thickness 0.1524)
				)
			)
		)
		(duplicate_pad_numbers_are_jumpers no)
		(fp_rect
			(start -0.4318 0.9525)
			(end 0.4318 -0.9525)
			(stroke
				(width 0)
				(type default)
			)
			(fill no)
			(layer "F.CrtYd")
		)
		(fp_rect
			(start -0.4318 0.9525)
			(end 0.4318 -0.9525)
			(stroke
				(width 0)
				(type default)
			)
			(fill no)
			(layer "F.Fab")
		)
		(pad "1" smd custom
			(at 0 -0.4445)
			(size 0.1524 0.1524)
			(layers "F.Cu" "F.Mask" "F.Paste")
			(net "HDD_PRSNT_28")
			(options
				(clearance outline)
				(anchor circle)
			)
			(primitives
				(gr_poly
					(pts
						(arc
							(start 0.3048 -0.2032)
							(mid 0.275042 -0.275042)
							(end 0.2032 -0.3048)
						)
						(arc
							(start -0.2032 -0.3048)
							(mid -0.275042 -0.275042)
							(end -0.3048 -0.2032)
						)
						(arc
							(start -0.3048 0.2032)
							(mid -0.275042 0.275042)
							(end -0.2032 0.3048)
						)
						(arc
							(start 0.2032 0.3048)
							(mid 0.275042 0.275042)
							(end 0.3048 0.2032)
						)
					)
					(width 0)
					(fill yes)
				)
			)
		)
		(pad "2" smd custom
			(at 0 0.4445)
			(size 0.1524 0.1524)
			(layers "F.Cu" "F.Mask" "F.Paste")
			(net "GND")
			(options
				(clearance outline)
				(anchor circle)
			)
			(primitives
				(gr_poly
					(pts
						(arc
							(start 0.3048 -0.2032)
							(mid 0.275042 -0.275042)
							(end 0.2032 -0.3048)
						)
						(arc
							(start -0.2032 -0.3048)
							(mid -0.275042 -0.275042)
							(end -0.3048 -0.2032)
						)
						(arc
							(start -0.3048 0.2032)
							(mid -0.275042 0.275042)
							(end -0.2032 0.3048)
						)
						(arc
							(start 0.2032 0.3048)
							(mid 0.275042 0.275042)
							(end 0.3048 0.2032)
						)
					)
					(width 0)
					(fill yes)
				)
			)
		)
	)
	(footprint ""
		(layer "F.Cu")
		(at 305.662076 -340.812882 180)
		(property "Reference" "R101"
			(at 0 0 180)
			(layer "F.SilkS")
			(hide yes)
			(effects
				(font
					(size 1.27 1.27)
				)
			)
		)
		(property "Value" "4K7R2F-GP"
			(at 0.064008 -3.993896 180)
			(unlocked yes)
			(layer "F.Fab")
			(hide yes)
			(effects
				(font
					(size 1.016 1.016)
					(thickness 0.1524)
				)
			)
		)
		(property "Device Type" "R402H16"
			(at 0.064008 -5.517896 180)
			(unlocked yes)
			(layer "F.Fab")
			(hide yes)
			(effects
				(font
					(size 1.016 1.016)
					(thickness 0.1524)
				)
			)
		)
		(duplicate_pad_numbers_are_jumpers no)
		(fp_line
			(start 0.508 -0.9398)
			(end -0.508 -0.9398)
			(stroke
				(width 0.1524)
				(type default)
			)
			(layer "F.SilkS")
		)
		(fp_line
			(start -0.508 -0.9398)
			(end -0.508 0.9398)
			(stroke
				(width 0.1524)
				(type default)
			)
			(layer "F.SilkS")
		)
		(fp_rect
			(start -0.508 0.9398)
			(end 0.508 -0.9398)
			(stroke
				(width 0)
				(type default)
			)
			(fill no)
			(layer "F.CrtYd")
		)
		(fp_rect
			(start -0.508 0.9398)
			(end 0.508 -0.9398)
			(stroke
				(width 0)
				(type default)
			)
			(fill no)
			(layer "F.Fab")
		)
		(pad "1" smd custom
			(at 0 -0.4445 180)
			(size 0.1397 0.1397)
			(layers "F.Cu" "F.Mask" "F.Paste")
			(net "PWM_CAMP_SEL1")
			(options
				(clearance outline)
				(anchor circle)
			)
			(primitives
				(gr_poly
					(pts
						(arc
							(start -0.1778 -0.2794)
							(mid -0.249642 -0.249642)
							(end -0.2794 -0.1778)
						)
						(arc
							(start -0.2794 0.1778)
							(mid -0.249642 0.249642)
							(end -0.1778 0.2794)
						)
						(arc
							(start 0.1778 0.2794)
							(mid 0.249642 0.249642)
							(end 0.2794 0.1778)
						)
						(arc
							(start 0.2794 -0.1778)
							(mid 0.249642 -0.249642)
							(end 0.1778 -0.2794)
						)
					)
					(width 0)
					(fill yes)
				)
			)
		)
		(pad "2" smd custom
			(at 0 0.4445 180)
			(size 0.1397 0.1397)
			(layers "F.Cu" "F.Mask" "F.Paste")
			(net "GND")
			(options
				(clearance outline)
				(anchor circle)
			)
			(primitives
				(gr_poly
					(pts
						(arc
							(start -0.1778 -0.2794)
							(mid -0.249642 -0.249642)
							(end -0.2794 -0.1778)
						)
						(arc
							(start -0.2794 0.1778)
							(mid -0.249642 0.249642)
							(end -0.1778 0.2794)
						)
						(arc
							(start 0.1778 0.2794)
							(mid 0.249642 0.249642)
							(end 0.2794 0.1778)
						)
						(arc
							(start 0.2794 -0.1778)
							(mid 0.249642 -0.249642)
							(end 0.1778 -0.2794)
						)
					)
					(width 0)
					(fill yes)
				)
			)
		)
	)
	(footprint ""
		(layer "F.Cu")
		(at 280.4414 -348.2848 90)
		(property "Reference" "R1073"
			(at 0 0 90)
			(layer "F.SilkS")
			(hide yes)
			(effects
				(font
					(size 1.27 1.27)
				)
			)
		)
		(property "Value" "4K7R2F-GP"
			(at 0.064008 -3.993896 90)
			(unlocked yes)
			(layer "F.Fab")
			(hide yes)
			(effects
				(font
					(size 1.016 1.016)
					(thickness 0.1524)
				)
			)
		)
		(property "Device Type" "R402H16"
			(at 0.064008 -5.517896 90)
			(unlocked yes)
			(layer "F.Fab")
			(hide yes)
			(effects
				(font
					(size 1.016 1.016)
					(thickness 0.1524)
				)
			)
		)
		(duplicate_pad_numbers_are_jumpers no)
		(fp_line
			(start 0.508 -0.9398)
			(end -0.508 -0.9398)
			(stroke
				(width 0.1524)
				(type default)
			)
			(layer "F.SilkS")
		)
		(fp_line
			(start -0.508 -0.9398)
			(end -0.508 0.9398)
			(stroke
				(width 0.1524)
				(type default)
			)
			(layer "F.SilkS")
		)
		(fp_rect
			(start -0.508 0.9398)
			(end 0.508 -0.9398)
			(stroke
				(width 0)
				(type default)
			)
			(fill no)
			(layer "F.CrtYd")
		)
		(fp_rect
			(start -0.508 0.9398)
			(end 0.508 -0.9398)
			(stroke
				(width 0)
				(type default)
			)
			(fill no)
			(layer "F.Fab")
		)
		(pad "1" smd custom
			(at 0 -0.4445 90)
			(size 0.1397 0.1397)
			(layers "F.Cu" "F.Mask" "F.Paste")
			(net "P3V3_STBY_B")
			(options
				(clearance outline)
				(anchor circle)
			)
			(primitives
				(gr_poly
					(pts
						(arc
							(start -0.1778 -0.2794)
							(mid -0.249642 -0.249642)
							(end -0.2794 -0.1778)
						)
						(arc
							(start -0.2794 0.1778)
							(mid -0.249642 0.249642)
							(end -0.1778 0.2794)
						)
						(arc
							(start 0.1778 0.2794)
							(mid 0.249642 0.249642)
							(end 0.2794 0.1778)
						)
						(arc
							(start 0.2794 -0.1778)
							(mid 0.249642 -0.249642)
							(end 0.1778 -0.2794)
						)
					)
					(width 0)
					(fill yes)
				)
			)
		)
		(pad "2" smd custom
			(at 0 0.4445 90)
			(size 0.1397 0.1397)
			(layers "F.Cu" "F.Mask" "F.Paste")
			(net "MAX31790_B_FULL_SPEED")
			(options
				(clearance outline)
				(anchor circle)
			)
			(primitives
				(gr_poly
					(pts
						(arc
							(start -0.1778 -0.2794)
							(mid -0.249642 -0.249642)
							(end -0.2794 -0.1778)
						)
						(arc
							(start -0.2794 0.1778)
							(mid -0.249642 0.249642)
							(end -0.1778 0.2794)
						)
						(arc
							(start 0.1778 0.2794)
							(mid 0.249642 0.249642)
							(end 0.2794 0.1778)
						)
						(arc
							(start 0.2794 -0.1778)
							(mid 0.249642 -0.249642)
							(end 0.1778 -0.2794)
						)
					)
					(width 0)
					(fill yes)
				)
			)
		)
	)
	(footprint ""
		(layer "F.Cu")
		(at 479.044 -42.164)
		(property "Reference" "C490"
			(at 0 0 0)
			(layer "F.SilkS")
			(hide yes)
			(effects
				(font
					(size 1.27 1.27)
				)
			)
		)
		(property "Value" "SC4D7U25V5KX-1-GP"
			(at -0.0762 -6.1214 0)
			(unlocked yes)
			(layer "F.Fab")
			(hide yes)
			(effects
				(font
					(size 1.016 1.016)
					(thickness 0.1524)
				)
			)
		)
		(property "Device Type" "C805H58"
			(at -0.0762 -8.1534 0)
			(unlocked yes)
			(layer "F.Fab")
			(hide yes)
			(effects
				(font
					(size 1.016 1.016)
					(thickness 0.1524)
				)
			)
		)
		(duplicate_pad_numbers_are_jumpers no)
		(fp_line
			(start 0.635 0)
			(end -0.635 0)
			(stroke
				(width 0.508)
				(type default)
			)
			(layer "F.SilkS")
		)
		(fp_rect
			(start -0.9652 1.778)
			(end 0.9652 -1.778)
			(stroke
				(width 0)
				(type default)
			)
			(fill no)
			(layer "F.CrtYd")
		)
		(fp_poly
			(pts
				(xy -0.9652 -1.778) (xy 0.9652 -1.778) (xy 0.9652 1.778) (xy -0.9652 1.778)
			)
			(stroke
				(width 0)
				(type default)
			)
			(fill no)
			(layer "F.Fab")
		)
		(pad "1" smd rect
			(at 0 -0.9652)
			(size 1.397 1.143)
			(layers "F.Cu" "F.Mask" "F.Paste")
			(net "P12V_HDD35")
		)
		(pad "2" smd rect
			(at 0 0.9652)
			(size 1.397 1.143)
			(layers "F.Cu" "F.Mask" "F.Paste")
			(net "GND")
		)
	)
	(footprint ""
		(layer "F.Cu")
		(at 354.866702 -17.4371)
		(property "Reference" "VIA64"
			(at 0 0 0)
			(layer "F.SilkS")
			(hide yes)
			(effects
				(font
					(size 1.27 1.27)
				)
			)
		)
		(property "Value" "100OHM-8L-2D36MM-L16-GP"
			(at -3.4036 -0.4572 0)
			(unlocked yes)
			(layer "F.Fab")
			(hide yes)
			(effects
				(font
					(size 1.016 1.016)
					(thickness 0.1524)
				)
			)
		)
		(property "Device Type" "VIA-PCIE-4P-427097"
			(at -3.4036 -1.9812 0)
			(unlocked yes)
			(layer "F.Fab")
			(hide yes)
			(effects
				(font
					(size 1.016 1.016)
					(thickness 0.1524)
				)
			)
		)
		(duplicate_pad_numbers_are_jumpers no)
		(fp_rect
			(start -2.1336 0.4826)
			(end 2.1336 -0.4826)
			(stroke
				(width 0)
				(type default)
			)
			(fill no)
			(layer "F.CrtYd")
		)
		(fp_rect
			(start -2.1336 0.4826)
			(end 2.1336 -0.4826)
			(stroke
				(width 0)
				(type default)
			)
			(fill no)
			(layer "F.Fab")
		)
		(pad "1" thru_hole circle
			(at -1.651 0)
			(size 0.508 0.508)
			(drill 0.254)
			(layers "*.Cu" "*.Mask")
			(remove_unused_layers no)
			(net "GND")
			(clearance 0.2286)
			(thermal_gap 0.2286)
		)
		(pad "2" thru_hole circle
			(at -0.635 0)
			(size 0.508 0.508)
			(drill 0.254)
			(layers "*.Cu" "*.Mask")
			(remove_unused_layers no)
			(net "PHY_DRV_B_TO_SCC_B_31_DP")
			(clearance 0.2286)
			(thermal_gap 0.2286)
		)
		(pad "3" thru_hole circle
			(at 0.635 0)
			(size 0.508 0.508)
			(drill 0.254)
			(layers "*.Cu" "*.Mask")
			(remove_unused_layers no)
			(net "PHY_DRV_B_TO_SCC_B_31_DN")
			(clearance 0.2286)
			(thermal_gap 0.2286)
		)
		(pad "4" thru_hole circle
			(at 1.651 0)
			(size 0.508 0.508)
			(drill 0.254)
			(layers "*.Cu" "*.Mask")
			(remove_unused_layers no)
			(net "GND")
			(clearance 0.2286)
			(thermal_gap 0.2286)
		)
	)
	(footprint ""
		(layer "F.Cu")
		(at 95.563436 -130.21945 90)
		(property "Reference" "C210"
			(at 0 0 90)
			(layer "F.SilkS")
			(hide yes)
			(effects
				(font
					(size 1.27 1.27)
				)
			)
		)
		(property "Value" "SCD01U16V1KX-GP"
			(at -2.8321 -1.7399 90)
			(unlocked yes)
			(layer "F.Fab")
			(hide yes)
			(effects
				(font
					(size 1.016 1.016)
					(thickness 0.1524)
				)
			)
		)
		(property "Device Type" "C0201H13"
			(at -2.8321 -3.2639 90)
			(unlocked yes)
			(layer "F.Fab")
			(hide yes)
			(effects
				(font
					(size 1.016 1.016)
					(thickness 0.1524)
				)
			)
		)
		(duplicate_pad_numbers_are_jumpers no)
		(fp_rect
			(start -0.2794 0.6477)
			(end 0.2794 -0.6477)
			(stroke
				(width 0)
				(type default)
			)
			(fill no)
			(layer "F.CrtYd")
		)
		(fp_rect
			(start -0.2794 0.6477)
			(end 0.2794 -0.6477)
			(stroke
				(width 0)
				(type default)
			)
			(fill no)
			(layer "F.Fab")
		)
		(pad "1" smd custom
			(at 0 -0.2794 90)
			(size 0.0762 0.0762)
			(layers "F.Cu" "F.Mask" "F.Paste")
			(net "SAS_HDD_RX_N14")
			(options
				(clearance outline)
				(anchor circle)
			)
			(primitives
				(gr_poly
					(pts
						(arc
							(start 0.1524 -0.127)
							(mid 0.137521 -0.162921)
							(end 0.1016 -0.1778)
						)
						(arc
							(start -0.1016 -0.1778)
							(mid -0.137521 -0.162921)
							(end -0.1524 -0.127)
						)
						(arc
							(start -0.1524 0.127)
							(mid -0.137521 0.162921)
							(end -0.1016 0.1778)
						)
						(arc
							(start 0.1016 0.1778)
							(mid 0.137521 0.162921)
							(end 0.1524 0.127)
						)
					)
					(width 0)
					(fill yes)
				)
			)
		)
		(pad "2" smd custom
			(at 0 0.2794 90)
			(size 0.0762 0.0762)
			(layers "F.Cu" "F.Mask" "F.Paste")
			(net "PHY_SCC_B_TO_DRV_B_14_DN")
			(options
				(clearance outline)
				(anchor circle)
			)
			(primitives
				(gr_poly
					(pts
						(arc
							(start 0.1524 -0.127)
							(mid 0.137521 -0.162921)
							(end 0.1016 -0.1778)
						)
						(arc
							(start -0.1016 -0.1778)
							(mid -0.137521 -0.162921)
							(end -0.1524 -0.127)
						)
						(arc
							(start -0.1524 0.127)
							(mid -0.137521 0.162921)
							(end -0.1016 0.1778)
						)
						(arc
							(start 0.1016 0.1778)
							(mid 0.137521 0.162921)
							(end 0.1524 0.127)
						)
					)
					(width 0)
					(fill yes)
				)
			)
		)
	)
)
